FILE_TYPE = CONNECTIVITY;
{Allegro Design Entry HDL 17.4-2019 S026 (4007227) 1/17/2022}
"PAGE_NUMBER" = 183;
0"NC";
1"GND\g";
2"GND\g";
3"GND\g";
4"GND\g";
5"GND\g";
6"P5V_AUX\g";
7"GND\g";
8"GND\g";
9"GND\g";
10"GND\g";
11"P3V3_AUX\g";
12"GND\g";
13"GND\g";
14"PVDD11_S3_P0_TEMP0";
15"PVDD11_S3_P0_VCC1";
16"SW_PVDD11_S3_P0_SW1";
17"GND\g";
18"PVDD11_S3_P0_PWM1";
19"PVDD11_S3_P0_LSET2";
20"NC_PVDD11_S3_P0_GL2_1";
21"SW_PVDD11_S3_P0_PH1";
22"P12V_AUX\g";
23"GND\g";
24"PVDD11_S3_P0_PVCC\g";
25"GND\g";
26"PVDD11_S3_P0_PVCC\g";
27"GND\g";
28"SW_P12V_AUX_PVDD11_S3_P0_FLT\g";
29"GND\g";
30"PVDD11_S3_P0\g";
31"GND\g";
32"PVDD11_S3_P0\g";
33"GND\g";
34"PVDD11_S3_P0\g";
35"GND\g";
36"PVDD11_S3_P0\g";
37"PVDD11_S3_P0_VOS1";
38"SW_PVDD11_S3_P0_BOOT1";
39"SW_PVDD11_S3_P0_BOOT1_RC";
40"SW_PVDD11_S3_P0_BOOT2";
41"SW_PVDD11_S3_P0_BOOT2_RC";
42"PVDD11_S3_P0_VCCS";
43"PVDD11_S3_P0_PWM2";
44"NC_PVDD11_S3_P0_DNC2";
45"PVDD11_S3_P0_TEMP0";
46"PVDD11_S3_P0_IMON2";
47"PVDD11_S3_P0_VCC2";
48"NC_PVDD11_S3_P0_GL2_2";
49"NC_PVDD11_S3_P0_GL1_2";
50"SW_PVDD11_S3_P0_SW2";
51"SW_PVDD11_S3_P0_SW2_RC";
52"PVDD11_S3_P0_VOS2";
53"SW_PVDD11_S3_P0_SW1_RC";
54"PVDD11_S3_P0_VCCS";
55"PVDD11_S3_P0_IMON1";
56"NC_PVDD11_S3_P0_DNC1";
57"PVDD11_S3_P0_LSET1";
58"SW_PVDD11_S3_P0_PH2";
59"NC_PVDD11_S3_P0_GL1_1";
60"SW_P12V_AUX_PVDD11_S3_P0_FLT\g";
%"UNIVERSAL_GND"
"1","(-7500,1025)","0","pure_quanta_power","I10";
;
CDS_LIB"pure_quanta_power"
HDL_POWER"GND";
"A"1;
%"Q_RES"
"1","(-7175,1200)","0","pure_quanta","I11";
;
LOCATION"PR134"
$SEC"1"
CDS_SEC"1"
PACK_TYPE"0402LF"
MATERIAL"EMPTY"
TOLERANCE"1%"
VALUE"4.87K"
WATTAGE"1/16W"
CDS_LIB"pure_quanta"
PART_NUMBER"CS24872FB01";
"B"
$PN"2"19;
"A"
$PN"1"1;
%"ISL99390FRZTR5935"
"1","(-6000,1500)","0","pure_quanta","I13";
;
LOCATION"PU23"
$SEC"1"
CDS_SEC"1"
PART_TYPE"SMLF"
VALUE"ISL99390FRZ-TR5935"
MATERIAL"IC"
CDS_LIB"pure_quanta"
NEEDS_NO_SIZE"TRUE"
CDS_LMAN_SYM_OUTLINE"-300,700,250,-650"
PART_NUMBER"AL099390004";
"PGND2"
$PN"7_9-20_24"25;
"GL2"
$PN"41"48;
"GL1"
$PN"6"49;
"DNC"
$PN"31"44;
"EN"
$PN"35"47;
"PGND3"
$PN"40"25;
"VOS"
$PN"1"52;
"VIN2"
$PN"30"28;
"PGND1"
$PN"5"25;
"SW"
$PN"10_19"50;
"LSET"
$PN"37"19;
"IOUT"
$PN"38"46;
"TOUT_FLT"
$PN"36"45;
"PVCC"
$PN"4"24;
"PHASE"
$PN"32"58;
"VIN1"
$PN"25_29"28;
"BOOT"
$PN"33"40;
"AGND"
$PN"2"25;
"VCC"
$PN"3"47;
"REFIN"
$PN"39"42;
"PWM"
$PN"34"43;
%"Q_RES"
"2","(-7775,2375)","0","pure_quanta","I14";
;
LOCATION"PR132"
$SEC"1"
CDS_SEC"1"
TOLERANCE"1%"
WATTAGE"1/16W"
MATERIAL"CHIP"
VALUE"2.2"
PACK_TYPE"0402LF"
CDS_LIB"pure_quanta"
PART_NUMBER"CS-2202FB01";
"A"
$PN"1"24;
"B"
$PN"2"47;
%"VCC_CORE"
"1","(-7775,2800)","0","pure_quanta_power","I15";
;
HDL_POWER"PVDD11_S3_P0_PVCC"
CDS_LIB"pure_quanta_power";
"A"24;
%"UNIVERSAL_GND"
"1","(-7425,2125)","0","pure_quanta_power","I16";
;
CDS_LIB"pure_quanta_power"
HDL_POWER"GND";
"A"2;
%"Q_CAP"
"1","(-7425,2400)","0","pure_quanta","I17";
;
LOCATION"PC206_11P0_2"
$SEC"1"
CDS_SEC"1"
PACK_TYPE"C0402"
VOLTAGE"10V"
VALUE"2.2UF"
TOLERANCE"10%"
MATERIAL"X6S"
CDS_LIB"pure_quanta"
PART_NUMBER"CH5222KEB01";
"B"
$PN"2"2;
"A"
$PN"1"24;
%"UNIVERSAL_GND"
"1","(-7875,3875)","0","pure_quanta_power","I18";
;
CDS_LIB"pure_quanta_power"
HDL_POWER"GND";
"A"3;
%"UNIVERSAL_GND"
"1","(-7525,3950)","0","pure_quanta_power","I19";
;
CDS_LIB"pure_quanta_power"
HDL_POWER"GND";
"A"4;
%"UNIVERSAL_GND"
"1","(-5425,775)","0","pure_quanta_power","I22";
;
CDS_LIB"pure_quanta_power"
HDL_POWER"GND";
"A"25;
%"UNIVERSAL_GND"
"1","(-4550,600)","0","pure_quanta_power","I23";
;
CDS_LIB"pure_quanta_power"
HDL_POWER"GND";
"A"5;
%"Q_RES"
"2","(-4550,825)","0","pure_quanta","I24";
;
LOCATION"PR389"
$SEC"1"
CDS_SEC"1"
MATERIAL"EMPTY"
PACK_TYPE"0402LF"
VALUE"1.5"
TOLERANCE"1%"
WATTAGE"1/8W"
CDS_LIB"pure_quanta"
PART_NUMBER"CS-1504FB00";
"A"
$PN"1"51;
"B"
$PN"2"5;
%"Q_RES"
"1","(-4675,1850)","0","pure_quanta","I25";
;
LOCATION"PR136"
$SEC"1"
CDS_SEC"1"
VALUE"5.6"
TOLERANCE"1%"
PACK_TYPE"0402LF"
WATTAGE"1/16W"
MATERIAL"CHIP"
CDS_LIB"pure_quanta"
PART_NUMBER"CS-5602FB01";
"B"
$PN"2"41;
"A"
$PN"1"40;
%"Q_CAP"
"1","(-4550,1300)","0","pure_quanta","I26";
;
LOCATION"PC168"
$SEC"1"
CDS_SEC"1"
VOLTAGE"50V"
TOLERANCE"10%"
MATERIAL"EMPTY"
PACK_TYPE"C0402"
VALUE"560PF"
CDS_LIB"pure_quanta"
PART_NUMBER"CH1566K1B09";
"B"
$PN"2"51;
"A"
$PN"1"50;
%"Q_CAP"
"1","(-5325,2400)","0","pure_quanta","I27";
;
LOCATION"PC210_2"
$SEC"1"
CDS_SEC"1"
TOLERANCE"10%"
VALUE"1UF"
PACK_TYPE"C0402"
VOLTAGE"25V"
MATERIAL"X6S"
CDS_LIB"pure_quanta"
PART_NUMBER"CH5104KEB02";
"B"
$PN"2"27;
"A"
$PN"1"28;
%"UNIVERSAL_GND"
"1","(-5425,3700)","0","pure_quanta_power","I28";
;
CDS_LIB"pure_quanta_power"
HDL_POWER"GND";
"A"17;
%"Q_CAP"
"1","(-5000,2400)","0","pure_quanta","I29";
;
LOCATION"PC208_2"
$SEC"1"
CDS_SEC"1"
TOLERANCE"10%"
VALUE"0.1UF"
VOLTAGE"25V"
MATERIAL"X7R"
PACK_TYPE"0402"
CDS_LIB"pure_quanta"
PART_NUMBER"CH4104K1B00";
"B"
$PN"2"27;
"A"
$PN"1"28;
%"VCC_CORE"
"1","(-8425,5900)","0","pure_quanta_power","I3";
;
HDL_POWER"P5V_AUX"
CDS_LIB"pure_quanta_power";
"A"6;
%"Q_CAP"
"1","(-4675,2400)","0","pure_quanta","I30";
;
LOCATION"PC212_2"
$SEC"1"
CDS_SEC"1"
VOLTAGE"16V"
PACK_TYPE"C0805"
VALUE"22UF"
TOLERANCE"20%"
MATERIAL"X6S"
CDS_LIB"pure_quanta"
PART_NUMBER"CH6223MEA01";
"B"
$PN"2"27;
"A"
$PN"1"28;
%"Q_CAP"
"1","(-4375,2400)","0","pure_quanta","I31";
;
LOCATION"PC214_2"
$SEC"1"
CDS_SEC"1"
MATERIAL"X6S"
TOLERANCE"20%"
VOLTAGE"16V"
PACK_TYPE"C0805"
VALUE"22UF"
CDS_LIB"pure_quanta"
PART_NUMBER"CH6223MEA01";
"B"
$PN"2"27;
"A"
$PN"1"28;
%"UNIVERSAL_GND"
"1","(-4650,3525)","0","pure_quanta_power","I32";
;
CDS_LIB"pure_quanta_power"
HDL_POWER"GND";
"A"7;
%"Q_RES"
"2","(-4650,3750)","0","pure_quanta","I33";
;
LOCATION"PR482"
$SEC"1"
CDS_SEC"1"
PACK_TYPE"0402LF"
WATTAGE"1/8W"
VALUE"1.5"
TOLERANCE"1%"
MATERIAL"EMPTY"
CDS_LIB"pure_quanta"
PART_NUMBER"CS-1504FB00";
"A"
$PN"1"53;
"B"
$PN"2"7;
%"Q_CAP"
"1","(-7875,4150)","0","pure_quanta","I34";
;
LOCATION"PC201_1"
$SEC"1"
CDS_SEC"1"
PACK_TYPE"0402"
VOLTAGE"25V"
VALUE"0.1UF"
TOLERANCE"10%"
MATERIAL"X7R"
CDS_LIB"pure_quanta"
PART_NUMBER"CH4104K1B00";
"B"
$PN"2"3;
"A"
$PN"1"54;
%"UNIVERSAL_GND"
"1","(-7775,4550)","0","pure_quanta_power","I35";
;
CDS_LIB"pure_quanta_power"
HDL_POWER"GND";
"A"8;
%"Q_CAP"
"1","(-7775,4750)","0","pure_quanta","I36";
;
LOCATION"PC203"
$SEC"1"
CDS_SEC"1"
VALUE"2.2UF"
PACK_TYPE"C0402"
VOLTAGE"10V"
TOLERANCE"10%"
MATERIAL"X6S"
CDS_LIB"pure_quanta"
PART_NUMBER"CH5222KEB01";
"B"
$PN"2"8;
"A"
$PN"1"15;
%"Q_RES"
"1","(-7200,4125)","0","pure_quanta","I37";
;
LOCATION"PR133"
$SEC"1"
CDS_SEC"1"
PACK_TYPE"0402LF"
VALUE"4.87K"
TOLERANCE"1%"
MATERIAL"EMPTY"
WATTAGE"1/16W"
CDS_LIB"pure_quanta"
PART_NUMBER"CS24872FB01";
"B"
$PN"2"57;
"A"
$PN"1"4;
%"UNIVERSAL_GND"
"1","(-7425,5050)","0","pure_quanta_power","I39";
;
CDS_LIB"pure_quanta_power"
HDL_POWER"GND";
"A"9;
%"UNIVERSAL_GND"
"1","(-7825,950)","0","pure_quanta_power","I4";
;
CDS_LIB"pure_quanta_power"
HDL_POWER"GND";
"A"10;
%"Q_RES"
"2","(-7775,5300)","0","pure_quanta","I40";
;
LOCATION"PR131"
$SEC"1"
CDS_SEC"1"
WATTAGE"1/16W"
MATERIAL"CHIP"
TOLERANCE"1%"
VALUE"2.2"
PACK_TYPE"0402LF"
CDS_LIB"pure_quanta"
PART_NUMBER"CS-2202FB01";
"A"
$PN"1"26;
"B"
$PN"2"15;
%"VCC_CORE"
"1","(-8075,5900)","0","pure_quanta_power","I41";
;
HDL_POWER"P3V3_AUX"
CDS_LIB"pure_quanta_power";
"A"11;
%"Q_CAP"
"1","(-7425,5325)","0","pure_quanta","I42";
;
LOCATION"PC205_11P0_1"
$SEC"1"
CDS_SEC"1"
PACK_TYPE"C0402"
VOLTAGE"10V"
VALUE"2.2UF"
TOLERANCE"10%"
MATERIAL"X6S"
CDS_LIB"pure_quanta"
PART_NUMBER"CH5222KEB01";
"B"
$PN"2"9;
"A"
$PN"1"26;
%"VCC_CORE"
"1","(-7575,5900)","0","pure_quanta_power","I43";
;
HDL_POWER"PVDD11_S3_P0_PVCC"
CDS_LIB"pure_quanta_power";
"A"26;
%"Q_CAP"
"1","(-5375,5325)","0","pure_quanta","I44";
;
LOCATION"PC209_1"
$SEC"1"
CDS_SEC"1"
VALUE"1UF"
VOLTAGE"25V"
TOLERANCE"10%"
PACK_TYPE"C0402"
MATERIAL"X6S"
CDS_LIB"pure_quanta"
PART_NUMBER"CH5104KEB02";
"B"
$PN"2"23;
"A"
$PN"1"60;
%"Q_CAP"
"1","(-4650,4225)","0","pure_quanta","I45";
;
LOCATION"PC169"
$SEC"1"
CDS_SEC"1"
PACK_TYPE"C0402"
TOLERANCE"10%"
VOLTAGE"50V"
MATERIAL"EMPTY"
VALUE"560PF"
CDS_LIB"pure_quanta"
PART_NUMBER"CH1566K1B09";
"B"
$PN"2"53;
"A"
$PN"1"16;
%"Q_RES"
"1","(-4750,4775)","0","pure_quanta","I46";
;
LOCATION"PR135"
$SEC"1"
CDS_SEC"1"
MATERIAL"CHIP"
PACK_TYPE"0402LF"
TOLERANCE"1%"
WATTAGE"1/16W"
VALUE"5.6"
CDS_LIB"pure_quanta"
PART_NUMBER"CS-5602FB01";
"B"
$PN"2"39;
"A"
$PN"1"38;
%"Q_CAP"
"1","(-5050,5325)","0","pure_quanta","I47";
;
LOCATION"PC207_1"
$SEC"1"
CDS_SEC"1"
VOLTAGE"25V"
TOLERANCE"10%"
MATERIAL"X7R"
VALUE"0.1UF"
PACK_TYPE"0402"
CDS_LIB"pure_quanta"
PART_NUMBER"CH4104K1B00";
"B"
$PN"2"23;
"A"
$PN"1"60;
%"Q_CAP"
"1","(-4750,5325)","0","pure_quanta","I48";
;
LOCATION"PC211_1"
$SEC"1"
CDS_SEC"1"
VOLTAGE"16V"
PACK_TYPE"C0805"
MATERIAL"X6S"
VALUE"22UF"
TOLERANCE"20%"
CDS_LIB"pure_quanta"
PART_NUMBER"CH6223MEA01";
"B"
$PN"2"23;
"A"
$PN"1"60;
%"Q_CAP"
"1","(-4425,5325)","0","pure_quanta","I49";
;
LOCATION"PC213_1"
$SEC"1"
CDS_SEC"1"
VOLTAGE"16V"
VALUE"22UF"
PACK_TYPE"C0805"
TOLERANCE"20%"
MATERIAL"X6S"
CDS_LIB"pure_quanta"
PART_NUMBER"CH6223MEA01";
"B"
$PN"2"23;
"A"
$PN"1"60;
%"Q_CAP"
"1","(-4050,2400)","0","pure_quanta","I50";
;
LOCATION"PC216_2"
$SEC"1"
CDS_SEC"1"
MATERIAL"X6S"
VOLTAGE"16V"
VALUE"22UF"
TOLERANCE"20%"
PACK_TYPE"C0805"
CDS_LIB"pure_quanta"
PART_NUMBER"CH6223MEA01";
"B"
$PN"2"27;
"A"
$PN"1"28;
%"Q_CAP"
"1","(-3850,1725)","0","pure_quanta","I51";
;
LOCATION"PC218"
$SEC"1"
CDS_SEC"1"
PACK_TYPE"0402"
VOLTAGE"16V"
VALUE"0.22UF"
TOLERANCE"10%"
MATERIAL"X7R"
CDS_LIB"pure_quanta"
PART_NUMBER"CH4223K1B00";
"B"
$PN"2"58;
"A"
$PN"1"41;
%"Q_INDUCTOR"
"1","(-3375,1525)","0","pure_quanta","I52";
;
LOCATION"PL22"
$SEC"1"
CDS_SEC"1"
MATERIAL"IND"
PACK_TYPE"SMLF"
VALUE"90NH/155A"
NEEDS_NO_SIZE"TRUE"
CDS_LIB"pure_quanta"
PART_NUMBER"CVA90^0KZ13";
"1"
$PN"1"50;
"2"
$PN"2"32;
%"UNIVERSAL_GND"
"1","(-3700,2075)","0","pure_quanta_power","I53";
;
CDS_LIB"pure_quanta_power"
HDL_POWER"GND";
"A"27;
%"Q_CAP"
"1","(-3700,2400)","0","pure_quanta","I54";
;
LOCATION"PC218_2"
$SEC"1"
CDS_SEC"1"
MATERIAL"X6S"
VALUE"22UF"
PACK_TYPE"C0805"
TOLERANCE"20%"
VOLTAGE"16V"
CDS_LIB"pure_quanta"
PART_NUMBER"CH6223MEA01";
"B"
$PN"2"27;
"A"
$PN"1"28;
%"VCC_CORE"
"1","(-3700,2675)","0","pure_quanta_power","I55";
;
HDL_POWER"SW_P12V_AUX_PVDD11_S3_P0_FLT"
CDS_LIB"pure_quanta_power";
"A"28;
%"Q_RES"
"1","(-3775,3450)","0","pure_quanta","I56";
;
LOCATION"PR137"
$SEC"1"
CDS_SEC"1"
PACK_TYPE"0402LF"
TOLERANCE"5%"
WATTAGE"1/16W"
MATERIAL"CHIP"
VALUE"0"
CDS_LIB"pure_quanta"
PART_NUMBER"CS00002JB13";
"B"
$PN"2"36;
"A"
$PN"1"37;
%"UNIVERSAL_GND"
"1","(-2725,2525)","0","pure_quanta_power","I57";
;
CDS_LIB"pure_quanta_power"
HDL_POWER"GND";
"A"29;
%"Q_CAPP"
"1","(-2725,2850)","0","pure_quanta","I58";
;
LOCATION"PC223"
$SEC"1"
CDS_SEC"1"
VALUE"470UF"
PACK_TYPE"SMLF"
VOLTAGE"2.5V"
TOLERANCE"20%"
MATERIAL"SPCAP"
CDS_LIB"pure_quanta"
PART_NUMBER"CH747LM8825";
"A"
$PN"1"30;
"B"
$PN"2"29;
%"Q_CAPP"
"1","(-2400,2850)","0","pure_quanta","I59";
;
LOCATION"PC226"
$SEC"1"
CDS_SEC"1"
VOLTAGE"2.5V"
TOLERANCE"20%"
PACK_TYPE"SMLF"
VALUE"470UF"
MATERIAL"SPCAP"
CDS_LIB"pure_quanta"
PART_NUMBER"CH747LM8825";
"A"
$PN"1"30;
"B"
$PN"2"29;
%"VCC_CORE"
"1","(-2725,3100)","0","pure_quanta_power","I60";
;
HDL_POWER"PVDD11_S3_P0"
CDS_LIB"pure_quanta_power";
"A"30;
%"UNIVERSAL_GND"
"1","(-1950,975)","0","pure_quanta_power","I61";
;
CDS_LIB"pure_quanta_power"
HDL_POWER"GND";
"A"31;
%"Q_CAP"
"1","(-1950,1325)","0","pure_quanta","I62";
;
LOCATION"PC225_2"
$SEC"1"
CDS_SEC"1"
PACK_TYPE"C0805"
MATERIAL"X6S"
TOLERANCE"20%"
VALUE"22UF"
VOLTAGE"4V"
CDS_LIB"pure_quanta"
PART_NUMBER"CH622KMEA03";
"B"
$PN"2"31;
"A"
$PN"1"32;
%"VCC_CORE"
"1","(-1950,1650)","0","pure_quanta_power","I63";
;
HDL_POWER"PVDD11_S3_P0"
CDS_LIB"pure_quanta_power";
"A"32;
%"UNIVERSAL_GND"
"1","(-1675,2550)","0","pure_quanta_power","I64";
;
CDS_LIB"pure_quanta_power"
HDL_POWER"GND";
"A"33;
%"Q_CAPP"
"1","(-1675,2875)","0","pure_quanta","I65";
;
LOCATION"PC228"
$SEC"1"
CDS_SEC"1"
MATERIAL"ALUM"
VOLTAGE"2.5V"
PACK_TYPE"SMLF"
TOLERANCE"20%"
VALUE"390UF"
CDS_LIB"pure_quanta"
PART_NUMBER"CC7390JMZ13";
"A"
$PN"1"34;
"B"
$PN"2"33;
%"Q_CAPP"
"1","(-1350,2875)","0","pure_quanta","I66";
;
LOCATION"PC229"
$SEC"1"
CDS_SEC"1"
VOLTAGE"2.5V"
MATERIAL"ALUM"
TOLERANCE"20%"
VALUE"390UF"
PACK_TYPE"SMLF"
CDS_LIB"pure_quanta"
PART_NUMBER"CC7390JMZ13";
"A"
$PN"1"34;
"B"
$PN"2"33;
%"Q_CAPP"
"1","(-1050,2875)","0","pure_quanta","I67";
;
LOCATION"PC230"
$SEC"1"
CDS_SEC"1"
PACK_TYPE"SMLF"
MATERIAL"ALUM"
TOLERANCE"20%"
VALUE"390UF"
VOLTAGE"2.5V"
CDS_LIB"pure_quanta"
PART_NUMBER"CC7390JMZ13";
"A"
$PN"1"34;
"B"
$PN"2"33;
%"VCC_CORE"
"1","(-1675,3100)","0","pure_quanta_power","I68";
;
HDL_POWER"PVDD11_S3_P0"
CDS_LIB"pure_quanta_power";
"A"34;
%"UNIVERSAL_GND"
"1","(-1200,3925)","0","pure_quanta_power","I69";
;
CDS_LIB"pure_quanta_power"
HDL_POWER"GND";
"A"35;
%"Q_CAP"
"1","(-7825,1225)","0","pure_quanta","I7";
;
LOCATION"PC202_2"
$SEC"1"
CDS_SEC"1"
PACK_TYPE"0402"
VOLTAGE"25V"
VALUE"0.1UF"
TOLERANCE"10%"
MATERIAL"X7R"
CDS_LIB"pure_quanta"
PART_NUMBER"CH4104K1B00";
"B"
$PN"2"10;
"A"
$PN"1"42;
%"Q_CAPP"
"1","(-700,2875)","0","pure_quanta","I70";
;
LOCATION"PC801"
$SEC"1"
CDS_SEC"1"
MATERIAL"ALUM"
TOLERANCE"20%"
VALUE"390UF"
VOLTAGE"2.5V"
PACK_TYPE"SMLF"
CDS_LIB"pure_quanta"
PART_NUMBER"CC7390JMZ13";
"A"
$PN"1"34;
"B"
$PN"2"33;
%"Q_CAP"
"1","(-3925,4650)","0","pure_quanta","I71";
;
LOCATION"PC217"
$SEC"1"
CDS_SEC"1"
TOLERANCE"10%"
PACK_TYPE"0402"
VALUE"0.22UF"
VOLTAGE"16V"
MATERIAL"X7R"
CDS_LIB"pure_quanta"
PART_NUMBER"CH4223K1B00";
"B"
$PN"2"21;
"A"
$PN"1"39;
%"UNIVERSAL_GND"
"1","(-3900,5000)","0","pure_quanta_power","I72";
;
CDS_LIB"pure_quanta_power"
HDL_POWER"GND";
"A"23;
%"Q_INDUCTOR"
"1","(-3275,4450)","0","pure_quanta","I73";
;
LOCATION"PL23"
$SEC"1"
CDS_SEC"1"
PACK_TYPE"SMLF"
MATERIAL"IND"
VALUE"90NH/155A"
CDS_LIB"pure_quanta"
NEEDS_NO_SIZE"TRUE"
PART_NUMBER"CVA90^0KZ13";
"1"
$PN"1"16;
"2"
$PN"2"36;
%"VCC_CORE"
"1","(-3900,5675)","0","pure_quanta_power","I74";
;
HDL_POWER"SW_P12V_AUX_PVDD11_S3_P0_FLT"
CDS_LIB"pure_quanta_power";
"A"60;
%"Q_CAPP"
"1","(-3250,5325)","0","pure_quanta","I75";
;
LOCATION"PC220"
$SEC"1"
CDS_SEC"1"
MATERIAL"OSCON"
VOLTAGE"16V"
PACK_TYPE"THLF"
TOLERANCE"20%"
VALUE"270UF"
CDS_LIB"pure_quanta"
PART_NUMBER"CC72703MD38";
"A"
$PN"1"60;
"B"
$PN"2"23;
%"Q_CAP"
"1","(-2300,4250)","0","pure_quanta","I76";
;
LOCATION"PC222"
$SEC"1"
CDS_SEC"1"
PACK_TYPE"0402"
VALUE"0.1UF"
TOLERANCE"10%"
MATERIAL"X7R"
VOLTAGE"25V"
CDS_LIB"pure_quanta"
PART_NUMBER"CH4104K1B00";
"B"
$PN"2"35;
"A"
$PN"1"36;
%"UNIVERSAL_GND"
"1","(-2275,4975)","0","pure_quanta_power","I77";
;
CDS_LIB"pure_quanta_power"
HDL_POWER"GND";
"A"12;
%"Q_INDUCTOR"
"1","(-2900,5525)","0","pure_quanta","I78";
;
LOCATION"PL24"
$SEC"1"
CDS_SEC"1"
MATERIAL"IND"
VALUE"100NH/16A"
PACK_TYPE"SMLF"
CDS_LIB"pure_quanta"
NEEDS_NO_SIZE"TRUE"
PART_NUMBER"CV+10G0MZ04";
"1"
$PN"1"60;
"2"
$PN"2"22;
%"Q_CAP"
"1","(-2275,5300)","0","pure_quanta","I79";
;
LOCATION"PC6003"
$SEC"1"
CDS_SEC"1"
VOLTAGE"25V"
TOLERANCE"10%"
MATERIAL"X7R"
VALUE"0.1UF"
PACK_TYPE"0402"
CDS_LIB"pure_quanta"
PART_NUMBER"CH4104K1B00";
"B"
$PN"2"12;
"A"
$PN"1"22;
%"UNIVERSAL_GND"
"1","(-7775,1625)","0","pure_quanta_power","I8";
;
CDS_LIB"pure_quanta_power"
HDL_POWER"GND";
"A"13;
%"VCC_CORE"
"1","(-2275,5700)","0","pure_quanta_power","I80";
;
HDL_POWER"P12V_AUX"
CDS_LIB"pure_quanta_power";
"A"22;
%"Q_CAP"
"1","(-1950,4250)","0","pure_quanta","I81";
;
LOCATION"PC224_1"
$SEC"1"
CDS_SEC"1"
PACK_TYPE"C0805"
MATERIAL"X6S"
TOLERANCE"20%"
VALUE"22UF"
VOLTAGE"4V"
CDS_LIB"pure_quanta"
PART_NUMBER"CH622KMEA03";
"B"
$PN"2"35;
"A"
$PN"1"36;
%"Q_CAP"
"1","(-1525,4250)","0","pure_quanta","I82";
;
LOCATION"PC227_1"
$SEC"1"
CDS_SEC"1"
PACK_TYPE"C0805"
MATERIAL"X6S"
TOLERANCE"20%"
VALUE"22UF"
VOLTAGE"4V"
CDS_LIB"pure_quanta"
PART_NUMBER"CH622KMEA03";
"B"
$PN"2"35;
"A"
$PN"1"36;
%"Q_RES"
"2","(-1200,4225)","0","pure_quanta","I83";
;
LOCATION"PR414"
$SEC"1"
CDS_SEC"1"
WATTAGE"1/16W"
MATERIAL"CHIP"
TOLERANCE"1%"
VALUE"1K"
PACK_TYPE"0402LF"
CDS_LIB"pure_quanta"
PART_NUMBER"CS21002FB06";
"A"
$PN"1"36;
"B"
$PN"2"35;
%"VCC_CORE"
"1","(-1200,4550)","0","pure_quanta_power","I84";
;
HDL_POWER"PVDD11_S3_P0"
CDS_LIB"pure_quanta_power";
"A"36;
%"Q_RES"
"1","(-8425,5700)","1","pure_quanta","I85";
;
LOCATION"PR411"
$SEC"1"
CDS_SEC"1"
WATTAGE"1/16W"
MATERIAL"CHIP"
TOLERANCE"5%"
VALUE"0"
PACK_TYPE"0402LF"
CDS_LIB"pure_quanta"
PART_NUMBER"CS00002JB13";
"B"
$PN"2"6;
"A"
$PN"1"26;
%"Q_RES"
"1","(-8075,5700)","1","pure_quanta","I86";
;
LOCATION"PR413"
$SEC"1"
CDS_SEC"1"
VALUE"0"
WATTAGE"1/16W"
MATERIAL"EMPTY"
TOLERANCE"5%"
PACK_TYPE"0402LF"
CDS_LIB"pure_quanta"
PART_NUMBER"CS00002JB13";
"B"
$PN"2"11;
"A"
$PN"1"26;
%"Q_CAP"
"1","(-4200,5325)","0","pure_quanta","I87";
;
LOCATION"PC215_1"
$SEC"1"
CDS_SEC"1"
VOLTAGE"16V"
VALUE"22UF"
PACK_TYPE"C0805"
MATERIAL"X6S"
TOLERANCE"20%"
CDS_LIB"pure_quanta"
PART_NUMBER"CH6223MEA01";
"B"
$PN"2"23;
"A"
$PN"1"60;
%"Q_CAP"
"1","(-4000,5325)","0","pure_quanta","I88";
;
LOCATION"PC219_1"
$SEC"1"
CDS_SEC"1"
VOLTAGE"16V"
VALUE"22UF"
TOLERANCE"20%"
MATERIAL"X6S"
PACK_TYPE"C0805"
CDS_LIB"pure_quanta"
PART_NUMBER"CH6223MEA01";
"B"
$PN"2"23;
"A"
$PN"1"60;
%"Q_CAPP"
"1","(-2075,2850)","0","pure_quanta","I89";
;
LOCATION"PC800"
$SEC"1"
CDS_SEC"1"
MATERIAL"SPCAP"
TOLERANCE"20%"
VALUE"470UF"
VOLTAGE"2.5V"
PACK_TYPE"SMLF"
CDS_LIB"pure_quanta"
PART_NUMBER"CH747LM8825";
"A"
$PN"1"30;
"B"
$PN"2"29;
%"Q_CAP"
"1","(-7775,1825)","0","pure_quanta","I9";
;
LOCATION"PC204"
$SEC"1"
CDS_SEC"1"
PACK_TYPE"C0402"
VOLTAGE"10V"
VALUE"2.2UF"
TOLERANCE"10%"
MATERIAL"X6S"
CDS_LIB"pure_quanta"
PART_NUMBER"CH5222KEB01";
"B"
$PN"2"13;
"A"
$PN"1"47;
%"Q_CAP"
"1","(-2375,1325)","0","pure_quanta","I90";
;
LOCATION"PC221_2"
$SEC"1"
CDS_SEC"1"
PACK_TYPE"C0805"
MATERIAL"X6S"
TOLERANCE"20%"
VALUE"22UF"
VOLTAGE"4V"
CDS_LIB"pure_quanta"
PART_NUMBER"CH622KMEA03";
"B"
$PN"2"31;
"A"
$PN"1"32;
%"Q_RES"
"1","(-3450,550)","0","pure_quanta","I91";
;
LOCATION"PR138"
$SEC"1"
CDS_SEC"1"
PACK_TYPE"0402LF"
WATTAGE"1/16W"
MATERIAL"CHIP"
TOLERANCE"5%"
VALUE"0"
CDS_LIB"pure_quanta"
PART_NUMBER"CS00002JB13";
"B"
$PN"2"32;
"A"
$PN"1"52;
%"ISL99390FRZTR5935"
"1","(-6050,4425)","0","pure_quanta","I92";
;
LOCATION"PU22"
$SEC"1"
CDS_SEC"1"
MATERIAL"IC"
VALUE"ISL99390FRZ-TR5935"
PART_TYPE"SMLF"
CDS_LIB"pure_quanta"
NEEDS_NO_SIZE"TRUE"
CDS_LMAN_SYM_OUTLINE"-300,700,250,-650"
PART_NUMBER"AL099390004";
"PGND2"
$PN"7_9-20_24"17;
"GL2"
$PN"41"20;
"GL1"
$PN"6"59;
"DNC"
$PN"31"56;
"EN"
$PN"35"15;
"PGND3"
$PN"40"17;
"VOS"
$PN"1"37;
"VIN2"
$PN"30"60;
"PGND1"
$PN"5"17;
"SW"
$PN"10_19"16;
"LSET"
$PN"37"57;
"IOUT"
$PN"38"55;
"TOUT_FLT"
$PN"36"14;
"PVCC"
$PN"4"26;
"PHASE"
$PN"32"21;
"VIN1"
$PN"25_29"60;
"BOOT"
$PN"33"38;
"AGND"
$PN"2"17;
"VCC"
$PN"3"15;
"REFIN"
$PN"39"54;
"PWM"
$PN"34"18;
%"Q_CAP"
"1","(-3800,5325)","0","pure_quanta","I93";
;
LOCATION"PC8004"
$SEC"1"
CDS_SEC"1"
VOLTAGE"16V"
TOLERANCE"20%"
MATERIAL"X6S"
PACK_TYPE"C0805"
VALUE"22UF"
CDS_LIB"pure_quanta"
PART_NUMBER"CH6223MEA01";
"B"
$PN"2"23;
"A"
$PN"1"60;
%"Q_CAP"
"1","(-3375,2400)","0","pure_quanta","I94";
;
LOCATION"PC8005"
$SEC"1"
CDS_SEC"1"
VOLTAGE"16V"
TOLERANCE"20%"
MATERIAL"X6S"
VALUE"22UF"
PACK_TYPE"C0805"
CDS_LIB"pure_quanta"
PART_NUMBER"CH6223MEA01";
"B"
$PN"2"27;
"A"
$PN"1"28;
%"Q_CAP"
"1","(-3550,5325)","0","pure_quanta","I95";
;
LOCATION"PC7002"
$SEC"1"
CDS_SEC"1"
MATERIAL"X6S"
PACK_TYPE"C0805"
TOLERANCE"20%"
VOLTAGE"16V"
VALUE"22UF"
CDS_LIB"pure_quanta"
PART_NUMBER"CH6223MEA01";
"B"
$PN"2"23;
"A"
$PN"1"60;
END.
